(kicad_pcb
	(version 20260206)
	(generator "pcbnew")
	(generator_version "10.0")
	(general
		(thickness 1.6)
		(legacy_teardrops no)
	)
	(paper "A4")
	(title_block
		(title "04192023_DAF0TMB3IC0_F0TG_MB_C_brd_V02_OCP.brd")
		(comment 1 "Grand Teton / footprints 7109-7114 of 8354")
	)
	(layers
		(0 "F.Cu" signal "TOP")
		(4 "In1.Cu" signal "GND")
		(6 "In2.Cu" signal "IN1")
		(8 "In3.Cu" signal "GND1")
		(10 "In4.Cu" signal "IN2")
		(12 "In5.Cu" signal "GND2")
		(14 "In6.Cu" signal "IN3")
		(16 "In7.Cu" signal "GND3")
		(18 "In8.Cu" signal "VCC")
		(20 "In9.Cu" signal "VCC1")
		(22 "In10.Cu" signal "GND4")
		(24 "In11.Cu" signal "IN4")
		(26 "In12.Cu" signal "GND5")
		(28 "In13.Cu" signal "IN5")
		(30 "In14.Cu" signal "GND6")
		(32 "In15.Cu" signal "IN6")
		(34 "In16.Cu" signal "GND7")
		(2 "B.Cu" signal "BOTTOM")
		(9 "F.Adhes" user "F.Adhesive")
		(11 "B.Adhes" user "B.Adhesive")
		(13 "F.Paste" user "Package Geometry/Pastemask Top")
		(15 "B.Paste" user "Package Geometry/Pastemask Bottom")
		(5 "F.SilkS" user "Ref Des/Silkscreen Top")
		(7 "B.SilkS" user "Ref Des/Silkscreen Bottom")
		(1 "F.Mask" user "Board Geometry/Soldermask Top")
		(3 "B.Mask" user "Board Geometry/Soldermask Bottom")
		(17 "Dwgs.User" user "User.Drawings")
		(19 "Cmts.User" user "User.Comments")
		(21 "Eco1.User" user "User.Eco1")
		(23 "Eco2.User" user "User.Eco2")
		(25 "Edge.Cuts" user "Board Geometry/Outline")
		(27 "Margin" user)
		(31 "F.CrtYd" user "Package Geometry/Place Bound Top")
		(29 "B.CrtYd" user "Package Geometry/Place Bound Bottom")
		(35 "F.Fab" user "Ref Des/Assembly Top")
		(33 "B.Fab" user "Ref Des/Assembly Bottom")
	)
	(footprint ""
		(layer "B.Cu")
		(at 354.025454 -268.41831)
		(property "Reference" "C2229"
			(at 0 0 0)
			(layer "B.SilkS")
			(hide yes)
			(effects
				(font
					(size 1.27 1.27)
				)
				(justify mirror)
			)
		)
		(property "Value" ""
			(at 0 0 0)
			(layer "B.Fab")
			(effects
				(font
					(size 1.27 1.27)
				)
				(justify mirror)
			)
		)
		(duplicate_pad_numbers_are_jumpers no)
		(fp_line
			(start -0.7874 -0.4064)
			(end -0.7874 0.4064)
			(stroke
				(width 0.1524)
				(type default)
			)
			(layer "B.SilkS")
		)
		(fp_line
			(start -0.7874 0.4064)
			(end 0.7874 0.4064)
			(stroke
				(width 0.1524)
				(type default)
			)
			(layer "B.SilkS")
		)
		(fp_line
			(start 0.7874 -0.4064)
			(end -0.7874 -0.4064)
			(stroke
				(width 0.1524)
				(type default)
			)
			(layer "B.SilkS")
		)
		(fp_line
			(start 0.7874 0.4064)
			(end 0.7874 -0.4064)
			(stroke
				(width 0.1524)
				(type default)
			)
			(layer "B.SilkS")
		)
		(fp_line
			(start -0.67945 -0.3048)
			(end -0.67945 0.3048)
			(stroke
				(width 0.1)
				(type default)
			)
			(layer "B.Fab")
		)
		(fp_line
			(start -0.67945 0.3048)
			(end -0.120396 0.3048)
			(stroke
				(width 0.1)
				(type default)
			)
			(layer "B.Fab")
		)
		(fp_line
			(start -0.12065 -0.3048)
			(end -0.67945 -0.3048)
			(stroke
				(width 0.1)
				(type default)
			)
			(layer "B.Fab")
		)
		(fp_line
			(start -0.12065 -0.2794)
			(end -0.12065 -0.3048)
			(stroke
				(width 0.1)
				(type default)
			)
			(layer "B.Fab")
		)
		(fp_line
			(start -0.120396 0.2794)
			(end 0.12065 0.2794)
			(stroke
				(width 0.1)
				(type default)
			)
			(layer "B.Fab")
		)
		(fp_line
			(start -0.120396 0.3048)
			(end -0.120396 0.2794)
			(stroke
				(width 0.1)
				(type default)
			)
			(layer "B.Fab")
		)
		(fp_line
			(start 0.12065 -0.305054)
			(end 0.12065 -0.2794)
			(stroke
				(width 0.1)
				(type default)
			)
			(layer "B.Fab")
		)
		(fp_line
			(start 0.12065 -0.2794)
			(end -0.12065 -0.2794)
			(stroke
				(width 0.1)
				(type default)
			)
			(layer "B.Fab")
		)
		(fp_line
			(start 0.12065 0.2794)
			(end 0.12065 0.3048)
			(stroke
				(width 0.1)
				(type default)
			)
			(layer "B.Fab")
		)
		(fp_line
			(start 0.12065 0.3048)
			(end 0.67945 0.3048)
			(stroke
				(width 0.1)
				(type default)
			)
			(layer "B.Fab")
		)
		(fp_line
			(start 0.67945 -0.305054)
			(end 0.12065 -0.305054)
			(stroke
				(width 0.1)
				(type default)
			)
			(layer "B.Fab")
		)
		(fp_line
			(start 0.67945 0.3048)
			(end 0.67945 -0.305054)
			(stroke
				(width 0.1)
				(type default)
			)
			(layer "B.Fab")
		)
		(pad "1" smd circle
			(at 0.40005 0 180)
			(size 0 0)
			(layers "B.Cu" "B.Mask" "B.Paste")
			(net "PVDDCR_CPU1_P0")
		)
		(pad "2" smd circle
			(at -0.40005 0 180)
			(size 0 0)
			(layers "B.Cu" "B.Mask" "B.Paste")
			(net "GND")
		)
	)
	(footprint ""
		(layer "B.Cu")
		(at 58.19521 -244.085364)
		(property "Reference" "R500"
			(at 0 0 0)
			(layer "B.SilkS")
			(hide yes)
			(effects
				(font
					(size 1.27 1.27)
				)
				(justify mirror)
			)
		)
		(property "Value" ""
			(at 0 0 0)
			(layer "B.Fab")
			(effects
				(font
					(size 1.27 1.27)
				)
				(justify mirror)
			)
		)
		(duplicate_pad_numbers_are_jumpers no)
		(fp_line
			(start -0.7874 -0.4064)
			(end -0.7874 0.4064)
			(stroke
				(width 0.1524)
				(type default)
			)
			(layer "B.SilkS")
		)
		(fp_line
			(start -0.7874 0.4064)
			(end 0.7874 0.4064)
			(stroke
				(width 0.1524)
				(type default)
			)
			(layer "B.SilkS")
		)
		(fp_line
			(start 0.7874 -0.4064)
			(end -0.7874 -0.4064)
			(stroke
				(width 0.1524)
				(type default)
			)
			(layer "B.SilkS")
		)
		(fp_line
			(start 0.7874 0.4064)
			(end 0.7874 -0.4064)
			(stroke
				(width 0.1524)
				(type default)
			)
			(layer "B.SilkS")
		)
		(fp_line
			(start -0.67945 -0.3048)
			(end -0.67945 0.3048)
			(stroke
				(width 0.1)
				(type default)
			)
			(layer "B.Fab")
		)
		(fp_line
			(start -0.67945 0.3048)
			(end -0.120396 0.3048)
			(stroke
				(width 0.1)
				(type default)
			)
			(layer "B.Fab")
		)
		(fp_line
			(start -0.12065 -0.3048)
			(end -0.67945 -0.3048)
			(stroke
				(width 0.1)
				(type default)
			)
			(layer "B.Fab")
		)
		(fp_line
			(start -0.12065 -0.2794)
			(end -0.12065 -0.3048)
			(stroke
				(width 0.1)
				(type default)
			)
			(layer "B.Fab")
		)
		(fp_line
			(start -0.120396 0.2794)
			(end 0.12065 0.2794)
			(stroke
				(width 0.1)
				(type default)
			)
			(layer "B.Fab")
		)
		(fp_line
			(start -0.120396 0.3048)
			(end -0.120396 0.2794)
			(stroke
				(width 0.1)
				(type default)
			)
			(layer "B.Fab")
		)
		(fp_line
			(start 0.12065 -0.305054)
			(end 0.12065 -0.2794)
			(stroke
				(width 0.1)
				(type default)
			)
			(layer "B.Fab")
		)
		(fp_line
			(start 0.12065 -0.2794)
			(end -0.12065 -0.2794)
			(stroke
				(width 0.1)
				(type default)
			)
			(layer "B.Fab")
		)
		(fp_line
			(start 0.12065 0.2794)
			(end 0.12065 0.3048)
			(stroke
				(width 0.1)
				(type default)
			)
			(layer "B.Fab")
		)
		(fp_line
			(start 0.12065 0.3048)
			(end 0.67945 0.3048)
			(stroke
				(width 0.1)
				(type default)
			)
			(layer "B.Fab")
		)
		(fp_line
			(start 0.67945 -0.305054)
			(end 0.12065 -0.305054)
			(stroke
				(width 0.1)
				(type default)
			)
			(layer "B.Fab")
		)
		(fp_line
			(start 0.67945 0.3048)
			(end 0.67945 -0.305054)
			(stroke
				(width 0.1)
				(type default)
			)
			(layer "B.Fab")
		)
		(pad "1" smd circle
			(at 0.40005 0 180)
			(size 0 0)
			(layers "B.Cu" "B.Mask" "B.Paste")
			(net "M_A_CPU1_ALERT_N")
		)
		(pad "2" smd circle
			(at -0.40005 0 180)
			(size 0 0)
			(layers "B.Cu" "B.Mask" "B.Paste")
			(net "M_A_CPU1_ALERT_R_N")
		)
	)
	(footprint ""
		(layer "B.Cu")
		(at 300.304454 -190.82131)
		(property "Reference" "R291"
			(at 0 0 0)
			(layer "B.SilkS")
			(hide yes)
			(effects
				(font
					(size 1.27 1.27)
				)
				(justify mirror)
			)
		)
		(property "Value" ""
			(at 0 0 0)
			(layer "B.Fab")
			(effects
				(font
					(size 1.27 1.27)
				)
				(justify mirror)
			)
		)
		(duplicate_pad_numbers_are_jumpers no)
		(fp_line
			(start -0.7874 -0.4064)
			(end -0.7874 0.4064)
			(stroke
				(width 0.1524)
				(type default)
			)
			(layer "B.SilkS")
		)
		(fp_line
			(start -0.7874 0.4064)
			(end 0.7874 0.4064)
			(stroke
				(width 0.1524)
				(type default)
			)
			(layer "B.SilkS")
		)
		(fp_line
			(start 0.7874 -0.4064)
			(end -0.7874 -0.4064)
			(stroke
				(width 0.1524)
				(type default)
			)
			(layer "B.SilkS")
		)
		(fp_line
			(start 0.7874 0.4064)
			(end 0.7874 -0.4064)
			(stroke
				(width 0.1524)
				(type default)
			)
			(layer "B.SilkS")
		)
		(fp_line
			(start -0.67945 -0.3048)
			(end -0.67945 0.3048)
			(stroke
				(width 0.1)
				(type default)
			)
			(layer "B.Fab")
		)
		(fp_line
			(start -0.67945 0.3048)
			(end -0.120396 0.3048)
			(stroke
				(width 0.1)
				(type default)
			)
			(layer "B.Fab")
		)
		(fp_line
			(start -0.12065 -0.3048)
			(end -0.67945 -0.3048)
			(stroke
				(width 0.1)
				(type default)
			)
			(layer "B.Fab")
		)
		(fp_line
			(start -0.12065 -0.2794)
			(end -0.12065 -0.3048)
			(stroke
				(width 0.1)
				(type default)
			)
			(layer "B.Fab")
		)
		(fp_line
			(start -0.120396 0.2794)
			(end 0.12065 0.2794)
			(stroke
				(width 0.1)
				(type default)
			)
			(layer "B.Fab")
		)
		(fp_line
			(start -0.120396 0.3048)
			(end -0.120396 0.2794)
			(stroke
				(width 0.1)
				(type default)
			)
			(layer "B.Fab")
		)
		(fp_line
			(start 0.12065 -0.305054)
			(end 0.12065 -0.2794)
			(stroke
				(width 0.1)
				(type default)
			)
			(layer "B.Fab")
		)
		(fp_line
			(start 0.12065 -0.2794)
			(end -0.12065 -0.2794)
			(stroke
				(width 0.1)
				(type default)
			)
			(layer "B.Fab")
		)
		(fp_line
			(start 0.12065 0.2794)
			(end 0.12065 0.3048)
			(stroke
				(width 0.1)
				(type default)
			)
			(layer "B.Fab")
		)
		(fp_line
			(start 0.12065 0.3048)
			(end 0.67945 0.3048)
			(stroke
				(width 0.1)
				(type default)
			)
			(layer "B.Fab")
		)
		(fp_line
			(start 0.67945 -0.305054)
			(end 0.12065 -0.305054)
			(stroke
				(width 0.1)
				(type default)
			)
			(layer "B.Fab")
		)
		(fp_line
			(start 0.67945 0.3048)
			(end 0.67945 -0.305054)
			(stroke
				(width 0.1)
				(type default)
			)
			(layer "B.Fab")
		)
		(pad "1" smd circle
			(at 0.40005 0 180)
			(size 0 0)
			(layers "B.Cu" "B.Mask" "B.Paste")
			(net "PWRGD_CHA_CPU0_DIMM0")
		)
		(pad "2" smd circle
			(at -0.40005 0 180)
			(size 0 0)
			(layers "B.Cu" "B.Mask" "B.Paste")
			(net "PWRGD_CHAF_CPU0")
		)
	)
	(footprint ""
		(layer "B.Cu")
		(at 144.102582 -17.313148 90)
		(property "Reference" "R1546"
			(at 0 0 90)
			(layer "B.SilkS")
			(hide yes)
			(effects
				(font
					(size 1.27 1.27)
				)
				(justify mirror)
			)
		)
		(property "Value" ""
			(at 0 0 90)
			(layer "B.Fab")
			(effects
				(font
					(size 1.27 1.27)
				)
				(justify mirror)
			)
		)
		(duplicate_pad_numbers_are_jumpers no)
		(fp_line
			(start 0.7874 -0.4064)
			(end -0.7874 -0.4064)
			(stroke
				(width 0.1524)
				(type default)
			)
			(layer "B.SilkS")
		)
		(fp_line
			(start -0.7874 -0.4064)
			(end -0.7874 0.4064)
			(stroke
				(width 0.1524)
				(type default)
			)
			(layer "B.SilkS")
		)
		(fp_line
			(start 0.7874 0.4064)
			(end 0.7874 -0.4064)
			(stroke
				(width 0.1524)
				(type default)
			)
			(layer "B.SilkS")
		)
		(fp_line
			(start -0.7874 0.4064)
			(end 0.7874 0.4064)
			(stroke
				(width 0.1524)
				(type default)
			)
			(layer "B.SilkS")
		)
		(fp_line
			(start 0.67945 -0.305054)
			(end 0.12065 -0.305054)
			(stroke
				(width 0.1)
				(type default)
			)
			(layer "B.Fab")
		)
		(fp_line
			(start 0.12065 -0.305054)
			(end 0.12065 -0.2794)
			(stroke
				(width 0.1)
				(type default)
			)
			(layer "B.Fab")
		)
		(fp_line
			(start -0.12065 -0.3048)
			(end -0.67945 -0.3048)
			(stroke
				(width 0.1)
				(type default)
			)
			(layer "B.Fab")
		)
		(fp_line
			(start -0.67945 -0.3048)
			(end -0.67945 0.3048)
			(stroke
				(width 0.1)
				(type default)
			)
			(layer "B.Fab")
		)
		(fp_line
			(start 0.12065 -0.2794)
			(end -0.12065 -0.2794)
			(stroke
				(width 0.1)
				(type default)
			)
			(layer "B.Fab")
		)
		(fp_line
			(start -0.12065 -0.2794)
			(end -0.12065 -0.3048)
			(stroke
				(width 0.1)
				(type default)
			)
			(layer "B.Fab")
		)
		(fp_line
			(start 0.12065 0.2794)
			(end 0.12065 0.3048)
			(stroke
				(width 0.1)
				(type default)
			)
			(layer "B.Fab")
		)
		(fp_line
			(start -0.120396 0.2794)
			(end 0.12065 0.2794)
			(stroke
				(width 0.1)
				(type default)
			)
			(layer "B.Fab")
		)
		(fp_line
			(start 0.67945 0.3048)
			(end 0.67945 -0.305054)
			(stroke
				(width 0.1)
				(type default)
			)
			(layer "B.Fab")
		)
		(fp_line
			(start 0.12065 0.3048)
			(end 0.67945 0.3048)
			(stroke
				(width 0.1)
				(type default)
			)
			(layer "B.Fab")
		)
		(fp_line
			(start -0.120396 0.3048)
			(end -0.120396 0.2794)
			(stroke
				(width 0.1)
				(type default)
			)
			(layer "B.Fab")
		)
		(fp_line
			(start -0.67945 0.3048)
			(end -0.120396 0.3048)
			(stroke
				(width 0.1)
				(type default)
			)
			(layer "B.Fab")
		)
		(pad "1" smd circle
			(at 0.40005 0 270)
			(size 0 0)
			(layers "B.Cu" "B.Mask" "B.Paste")
			(net "P3V3_AUX")
		)
		(pad "2" smd circle
			(at -0.40005 0 270)
			(size 0 0)
			(layers "B.Cu" "B.Mask" "B.Paste")
			(net "RST_MB_STBY_N")
		)
	)
	(footprint ""
		(layer "B.Cu")
		(at 184.785 -144.399 180)
		(property "Reference" "U8000"
			(at 0.625602 -2.39903 0)
			(unlocked yes)
			(layer "B.SilkS")
			(effects
				(font
					(size 0.7874 0.5842)
					(thickness 0.1524)
				)
				(justify mirror)
			)
		)
		(property "Value" ""
			(at 0 0 0)
			(layer "B.Fab")
			(effects
				(font
					(size 1.27 1.27)
				)
				(justify mirror)
			)
		)
		(duplicate_pad_numbers_are_jumpers no)
		(fp_line
			(start 1.34493 1.100074)
			(end 1.34493 -1.100074)
			(stroke
				(width 0.1524)
				(type default)
			)
			(layer "B.SilkS")
		)
		(fp_line
			(start 1.34493 -1.100074)
			(end 0.420878 -1.100074)
			(stroke
				(width 0.1524)
				(type default)
			)
			(layer "B.SilkS")
		)
		(fp_line
			(start 0.420878 -1.100074)
			(end -0.039878 -0.592074)
			(stroke
				(width 0.1524)
				(type default)
			)
			(layer "B.SilkS")
		)
		(fp_line
			(start -0.039878 -0.592074)
			(end -0.420878 -1.100074)
			(stroke
				(width 0.1524)
				(type default)
			)
			(layer "B.SilkS")
		)
		(fp_line
			(start -0.420878 -1.100074)
			(end -1.35509 -1.100074)
			(stroke
				(width 0.1524)
				(type default)
			)
			(layer "B.SilkS")
		)
		(fp_line
			(start -1.35509 1.100074)
			(end 1.34493 1.100074)
			(stroke
				(width 0.1524)
				(type default)
			)
			(layer "B.SilkS")
		)
		(fp_line
			(start -1.35509 -1.100074)
			(end -1.35509 1.100074)
			(stroke
				(width 0.1524)
				(type default)
			)
			(layer "B.SilkS")
		)
		(fp_poly
			(pts
				(xy 1.867662 -1.667764) (xy 2.324608 -1.058164) (xy 1.486408 -0.906018)
			)
			(stroke
				(width 0)
				(type default)
			)
			(fill yes)
			(layer "B.SilkS")
		)
		(fp_line
			(start 0.674878 1.100074)
			(end 0.674878 -1.100074)
			(stroke
				(width 0.1)
				(type default)
			)
			(layer "B.Fab")
		)
		(fp_line
			(start 0.674878 -1.100074)
			(end -0.674878 -1.100074)
			(stroke
				(width 0.1)
				(type default)
			)
			(layer "B.Fab")
		)
		(fp_line
			(start -0.674878 1.100074)
			(end 0.674878 1.100074)
			(stroke
				(width 0.1)
				(type default)
			)
			(layer "B.Fab")
		)
		(fp_line
			(start -0.674878 -1.100074)
			(end -0.674878 1.100074)
			(stroke
				(width 0.1)
				(type default)
			)
			(layer "B.Fab")
		)
		(fp_poly
			(pts
				(xy 2.286 -1.030986) (xy 2.286 -0.268986) (xy 1.524 -0.649986)
			)
			(stroke
				(width 0)
				(type default)
			)
			(fill yes)
			(layer "B.Fab")
		)
		(pad "1" smd rect
			(at 0.94996 -0.649986 90)
			(size 0.4064 0.508)
			(layers "B.Cu" "B.Mask" "B.Paste")
			(net "ESPI_CPU0_ALERT_R1_N")
		)
		(pad "2" smd rect
			(at 0.94996 0 90)
			(size 0.4064 0.508)
			(layers "B.Cu" "B.Mask" "B.Paste")
			(net "GND")
		)
		(pad "3" smd rect
			(at 0.94996 0.649986 90)
			(size 0.4064 0.508)
			(layers "B.Cu" "B.Mask" "B.Paste")
			(net "ESPI_CPU0_ALERT_PLD_N")
		)
		(pad "4" smd rect
			(at -0.94996 0.649986 90)
			(size 0.4064 0.508)
			(layers "B.Cu" "B.Mask" "B.Paste")
			(net "ESPI_CPU0_ALERT_P0_N")
		)
		(pad "5" smd rect
			(at -0.94996 0 90)
			(size 0.4064 0.508)
			(layers "B.Cu" "B.Mask" "B.Paste")
			(net "P1V8_AUX")
		)
		(pad "6" smd rect
			(at -0.94996 -0.649986 90)
			(size 0.4064 0.508)
			(layers "B.Cu" "B.Mask" "B.Paste")
			(net "FM_ESPI_CPU0_ALERT_R_SEL")
		)
	)
	(footprint ""
		(layer "B.Cu")
		(at 284.82417 -350.65589 -90)
		(property "Reference" "PC187_3"
			(at 0 0 90)
			(layer "B.SilkS")
			(hide yes)
			(effects
				(font
					(size 1.27 1.27)
				)
				(justify mirror)
			)
		)
		(property "Value" ""
			(at 0 0 90)
			(layer "B.Fab")
			(effects
				(font
					(size 1.27 1.27)
				)
				(justify mirror)
			)
		)
		(duplicate_pad_numbers_are_jumpers no)
		(fp_line
			(start -1.524 0.762)
			(end 1.524 0.762)
			(stroke
				(width 0.1524)
				(type default)
			)
			(layer "B.SilkS")
		)
		(fp_line
			(start 1.524 0.762)
			(end 1.524 -0.762)
			(stroke
				(width 0.1524)
				(type default)
			)
			(layer "B.SilkS")
		)
		(fp_line
			(start -1.524 -0.762)
			(end -1.524 0.762)
			(stroke
				(width 0.1524)
				(type default)
			)
			(layer "B.SilkS")
		)
		(fp_line
			(start 1.524 -0.762)
			(end -1.524 -0.762)
			(stroke
				(width 0.1524)
				(type default)
			)
			(layer "B.SilkS")
		)
		(fp_line
			(start -1.1049 0.724916)
			(end -1.1049 -0.724916)
			(stroke
				(width 0.1)
				(type default)
			)
			(layer "B.Fab")
		)
		(fp_line
			(start 1.1049 0.724916)
			(end -1.1049 0.724916)
			(stroke
				(width 0.1)
				(type default)
			)
			(layer "B.Fab")
		)
		(fp_line
			(start -1.1049 -0.724916)
			(end 1.1049 -0.724916)
			(stroke
				(width 0.1)
				(type default)
			)
			(layer "B.Fab")
		)
		(fp_line
			(start 1.1049 -0.724916)
			(end 1.1049 0.724916)
			(stroke
				(width 0.1)
				(type default)
			)
			(layer "B.Fab")
		)
		(pad "1" smd rect
			(at 0.889 0 270)
			(size 1.016 1.27)
			(layers "B.Cu" "B.Mask" "B.Paste")
			(net "SW_P12V_AUX_PVDDIO_P0_FLT")
		)
		(pad "2" smd rect
			(at -0.889 0 270)
			(size 1.016 1.27)
			(layers "B.Cu" "B.Mask" "B.Paste")
			(net "GND")
		)
	)
)
